(kicad_pcb
	(version 20260206)
	(generator "pcbnew")
	(generator_version "10.0")
	(general
		(thickness 1.6)
		(legacy_teardrops no)
	)
	(paper "A4")
	(title_block
		(title "04192023_DAF0TMB3IC0_F0TG_MB_C_brd_V02_OCP.brd")
		(comment 1 "Grand Teton / footprints 4065-4071 of 8354")
	)
	(layers
		(0 "F.Cu" signal "TOP")
		(4 "In1.Cu" signal "GND")
		(6 "In2.Cu" signal "IN1")
		(8 "In3.Cu" signal "GND1")
		(10 "In4.Cu" signal "IN2")
		(12 "In5.Cu" signal "GND2")
		(14 "In6.Cu" signal "IN3")
		(16 "In7.Cu" signal "GND3")
		(18 "In8.Cu" signal "VCC")
		(20 "In9.Cu" signal "VCC1")
		(22 "In10.Cu" signal "GND4")
		(24 "In11.Cu" signal "IN4")
		(26 "In12.Cu" signal "GND5")
		(28 "In13.Cu" signal "IN5")
		(30 "In14.Cu" signal "GND6")
		(32 "In15.Cu" signal "IN6")
		(34 "In16.Cu" signal "GND7")
		(2 "B.Cu" signal "BOTTOM")
		(9 "F.Adhes" user "F.Adhesive")
		(11 "B.Adhes" user "B.Adhesive")
		(13 "F.Paste" user "Package Geometry/Pastemask Top")
		(15 "B.Paste" user "Package Geometry/Pastemask Bottom")
		(5 "F.SilkS" user "Ref Des/Silkscreen Top")
		(7 "B.SilkS" user "Ref Des/Silkscreen Bottom")
		(1 "F.Mask" user "Board Geometry/Soldermask Top")
		(3 "B.Mask" user "Board Geometry/Soldermask Bottom")
		(17 "Dwgs.User" user "User.Drawings")
		(19 "Cmts.User" user "User.Comments")
		(21 "Eco1.User" user "User.Eco1")
		(23 "Eco2.User" user "User.Eco2")
		(25 "Edge.Cuts" user "Board Geometry/Outline")
		(27 "Margin" user)
		(31 "F.CrtYd" user "Package Geometry/Place Bound Top")
		(29 "B.CrtYd" user "Package Geometry/Place Bound Bottom")
		(35 "F.Fab" user "Ref Des/Assembly Top")
		(33 "B.Fab" user "Ref Des/Assembly Bottom")
	)
	(footprint ""
		(layer "F.Cu")
		(at 124.633228 -51.185064 180)
		(property "Reference" "C2317"
			(at 0 0 180)
			(layer "F.SilkS")
			(hide yes)
			(effects
				(font
					(size 1.27 1.27)
				)
			)
		)
		(property "Value" ""
			(at 0 0 180)
			(layer "F.Fab")
			(effects
				(font
					(size 1.27 1.27)
				)
			)
		)
		(duplicate_pad_numbers_are_jumpers no)
		(fp_line
			(start 0.7874 0.4064)
			(end -0.7874 0.4064)
			(stroke
				(width 0.1524)
				(type default)
			)
			(layer "F.SilkS")
		)
		(fp_line
			(start 0.7874 -0.4064)
			(end 0.7874 0.4064)
			(stroke
				(width 0.1524)
				(type default)
			)
			(layer "F.SilkS")
		)
		(fp_line
			(start -0.7874 0.4064)
			(end -0.7874 -0.4064)
			(stroke
				(width 0.1524)
				(type default)
			)
			(layer "F.SilkS")
		)
		(fp_line
			(start -0.7874 -0.4064)
			(end 0.7874 -0.4064)
			(stroke
				(width 0.1524)
				(type default)
			)
			(layer "F.SilkS")
		)
		(fp_line
			(start 0.67945 0.3048)
			(end 0.120396 0.3048)
			(stroke
				(width 0.1)
				(type default)
			)
			(layer "F.Fab")
		)
		(fp_line
			(start 0.67945 -0.3048)
			(end 0.67945 0.3048)
			(stroke
				(width 0.1)
				(type default)
			)
			(layer "F.Fab")
		)
		(fp_line
			(start 0.12065 -0.2794)
			(end 0.12065 -0.3048)
			(stroke
				(width 0.1)
				(type default)
			)
			(layer "F.Fab")
		)
		(fp_line
			(start 0.12065 -0.3048)
			(end 0.67945 -0.3048)
			(stroke
				(width 0.1)
				(type default)
			)
			(layer "F.Fab")
		)
		(fp_line
			(start 0.120396 0.3048)
			(end 0.120396 0.2794)
			(stroke
				(width 0.1)
				(type default)
			)
			(layer "F.Fab")
		)
		(fp_line
			(start 0.120396 0.2794)
			(end -0.12065 0.2794)
			(stroke
				(width 0.1)
				(type default)
			)
			(layer "F.Fab")
		)
		(fp_line
			(start -0.12065 0.3048)
			(end -0.67945 0.3048)
			(stroke
				(width 0.1)
				(type default)
			)
			(layer "F.Fab")
		)
		(fp_line
			(start -0.12065 0.2794)
			(end -0.12065 0.3048)
			(stroke
				(width 0.1)
				(type default)
			)
			(layer "F.Fab")
		)
		(fp_line
			(start -0.12065 -0.2794)
			(end 0.12065 -0.2794)
			(stroke
				(width 0.1)
				(type default)
			)
			(layer "F.Fab")
		)
		(fp_line
			(start -0.12065 -0.305054)
			(end -0.12065 -0.2794)
			(stroke
				(width 0.1)
				(type default)
			)
			(layer "F.Fab")
		)
		(fp_line
			(start -0.67945 0.3048)
			(end -0.67945 -0.305054)
			(stroke
				(width 0.1)
				(type default)
			)
			(layer "F.Fab")
		)
		(fp_line
			(start -0.67945 -0.305054)
			(end -0.12065 -0.305054)
			(stroke
				(width 0.1)
				(type default)
			)
			(layer "F.Fab")
		)
		(pad "1" smd circle
			(at -0.40005 0 180)
			(size 0 0)
			(layers "F.Cu" "F.Mask" "F.Paste")
			(net "RST_USB_CPU0_HUB1_R_N")
		)
		(pad "2" smd circle
			(at 0.40005 0 180)
			(size 0 0)
			(layers "F.Cu" "F.Mask" "F.Paste")
			(net "GND")
		)
	)
	(footprint ""
		(layer "F.Cu")
		(at 41.509696 -344.986864 90)
		(property "Reference" "PR489"
			(at 0 0 90)
			(layer "F.SilkS")
			(hide yes)
			(effects
				(font
					(size 1.27 1.27)
				)
			)
		)
		(property "Value" ""
			(at 0 0 90)
			(layer "F.Fab")
			(effects
				(font
					(size 1.27 1.27)
				)
			)
		)
		(duplicate_pad_numbers_are_jumpers no)
		(fp_line
			(start 0.7874 -0.4064)
			(end 0.7874 0.4064)
			(stroke
				(width 0.1524)
				(type default)
			)
			(layer "F.SilkS")
		)
		(fp_line
			(start -0.7874 -0.4064)
			(end 0.7874 -0.4064)
			(stroke
				(width 0.1524)
				(type default)
			)
			(layer "F.SilkS")
		)
		(fp_line
			(start 0.7874 0.4064)
			(end -0.7874 0.4064)
			(stroke
				(width 0.1524)
				(type default)
			)
			(layer "F.SilkS")
		)
		(fp_line
			(start -0.7874 0.4064)
			(end -0.7874 -0.4064)
			(stroke
				(width 0.1524)
				(type default)
			)
			(layer "F.SilkS")
		)
		(fp_line
			(start -0.12065 -0.305054)
			(end -0.12065 -0.2794)
			(stroke
				(width 0.1)
				(type default)
			)
			(layer "F.Fab")
		)
		(fp_line
			(start -0.67945 -0.305054)
			(end -0.12065 -0.305054)
			(stroke
				(width 0.1)
				(type default)
			)
			(layer "F.Fab")
		)
		(fp_line
			(start 0.67945 -0.3048)
			(end 0.67945 0.3048)
			(stroke
				(width 0.1)
				(type default)
			)
			(layer "F.Fab")
		)
		(fp_line
			(start 0.12065 -0.3048)
			(end 0.67945 -0.3048)
			(stroke
				(width 0.1)
				(type default)
			)
			(layer "F.Fab")
		)
		(fp_line
			(start 0.12065 -0.2794)
			(end 0.12065 -0.3048)
			(stroke
				(width 0.1)
				(type default)
			)
			(layer "F.Fab")
		)
		(fp_line
			(start -0.12065 -0.2794)
			(end 0.12065 -0.2794)
			(stroke
				(width 0.1)
				(type default)
			)
			(layer "F.Fab")
		)
		(fp_line
			(start 0.120396 0.2794)
			(end -0.12065 0.2794)
			(stroke
				(width 0.1)
				(type default)
			)
			(layer "F.Fab")
		)
		(fp_line
			(start -0.12065 0.2794)
			(end -0.12065 0.3048)
			(stroke
				(width 0.1)
				(type default)
			)
			(layer "F.Fab")
		)
		(fp_line
			(start 0.67945 0.3048)
			(end 0.120396 0.3048)
			(stroke
				(width 0.1)
				(type default)
			)
			(layer "F.Fab")
		)
		(fp_line
			(start 0.120396 0.3048)
			(end 0.120396 0.2794)
			(stroke
				(width 0.1)
				(type default)
			)
			(layer "F.Fab")
		)
		(fp_line
			(start -0.12065 0.3048)
			(end -0.67945 0.3048)
			(stroke
				(width 0.1)
				(type default)
			)
			(layer "F.Fab")
		)
		(fp_line
			(start -0.67945 0.3048)
			(end -0.67945 -0.305054)
			(stroke
				(width 0.1)
				(type default)
			)
			(layer "F.Fab")
		)
		(pad "1" smd circle
			(at -0.40005 0 90)
			(size 0 0)
			(layers "F.Cu" "F.Mask" "F.Paste")
			(net "SW_PVDDIO_P1_SW2_RC")
		)
		(pad "2" smd circle
			(at 0.40005 0 90)
			(size 0 0)
			(layers "F.Cu" "F.Mask" "F.Paste")
			(net "GND")
		)
	)
	(footprint ""
		(layer "F.Cu")
		(at 212.993732 -110.630208 180)
		(property "Reference" "R126"
			(at 0 0 180)
			(layer "F.SilkS")
			(hide yes)
			(effects
				(font
					(size 1.27 1.27)
				)
			)
		)
		(property "Value" ""
			(at 0 0 180)
			(layer "F.Fab")
			(effects
				(font
					(size 1.27 1.27)
				)
			)
		)
		(duplicate_pad_numbers_are_jumpers no)
		(fp_line
			(start 0.7874 0.4064)
			(end -0.7874 0.4064)
			(stroke
				(width 0.1524)
				(type default)
			)
			(layer "F.SilkS")
		)
		(fp_line
			(start 0.7874 -0.4064)
			(end 0.7874 0.4064)
			(stroke
				(width 0.1524)
				(type default)
			)
			(layer "F.SilkS")
		)
		(fp_line
			(start -0.7874 0.4064)
			(end -0.7874 -0.4064)
			(stroke
				(width 0.1524)
				(type default)
			)
			(layer "F.SilkS")
		)
		(fp_line
			(start -0.7874 -0.4064)
			(end 0.7874 -0.4064)
			(stroke
				(width 0.1524)
				(type default)
			)
			(layer "F.SilkS")
		)
		(fp_line
			(start 0.67945 0.3048)
			(end 0.120396 0.3048)
			(stroke
				(width 0.1)
				(type default)
			)
			(layer "F.Fab")
		)
		(fp_line
			(start 0.67945 -0.3048)
			(end 0.67945 0.3048)
			(stroke
				(width 0.1)
				(type default)
			)
			(layer "F.Fab")
		)
		(fp_line
			(start 0.12065 -0.2794)
			(end 0.12065 -0.3048)
			(stroke
				(width 0.1)
				(type default)
			)
			(layer "F.Fab")
		)
		(fp_line
			(start 0.12065 -0.3048)
			(end 0.67945 -0.3048)
			(stroke
				(width 0.1)
				(type default)
			)
			(layer "F.Fab")
		)
		(fp_line
			(start 0.120396 0.3048)
			(end 0.120396 0.2794)
			(stroke
				(width 0.1)
				(type default)
			)
			(layer "F.Fab")
		)
		(fp_line
			(start 0.120396 0.2794)
			(end -0.12065 0.2794)
			(stroke
				(width 0.1)
				(type default)
			)
			(layer "F.Fab")
		)
		(fp_line
			(start -0.12065 0.3048)
			(end -0.67945 0.3048)
			(stroke
				(width 0.1)
				(type default)
			)
			(layer "F.Fab")
		)
		(fp_line
			(start -0.12065 0.2794)
			(end -0.12065 0.3048)
			(stroke
				(width 0.1)
				(type default)
			)
			(layer "F.Fab")
		)
		(fp_line
			(start -0.12065 -0.2794)
			(end 0.12065 -0.2794)
			(stroke
				(width 0.1)
				(type default)
			)
			(layer "F.Fab")
		)
		(fp_line
			(start -0.12065 -0.305054)
			(end -0.12065 -0.2794)
			(stroke
				(width 0.1)
				(type default)
			)
			(layer "F.Fab")
		)
		(fp_line
			(start -0.67945 0.3048)
			(end -0.67945 -0.305054)
			(stroke
				(width 0.1)
				(type default)
			)
			(layer "F.Fab")
		)
		(fp_line
			(start -0.67945 -0.305054)
			(end -0.12065 -0.305054)
			(stroke
				(width 0.1)
				(type default)
			)
			(layer "F.Fab")
		)
		(pad "1" smd circle
			(at -0.40005 0 180)
			(size 0 0)
			(layers "F.Cu" "F.Mask" "F.Paste")
			(net "FM_APML_MUX2_OE_N")
		)
		(pad "2" smd circle
			(at 0.40005 0 180)
			(size 0 0)
			(layers "F.Cu" "F.Mask" "F.Paste")
			(net "GND")
		)
	)
	(footprint ""
		(layer "F.Cu")
		(at 44.668694 -16.099536 90)
		(property "Reference" "C699"
			(at 0 0 90)
			(layer "F.SilkS")
			(hide yes)
			(effects
				(font
					(size 1.27 1.27)
				)
			)
		)
		(property "Value" ""
			(at 0 0 90)
			(layer "F.Fab")
			(effects
				(font
					(size 1.27 1.27)
				)
			)
		)
		(duplicate_pad_numbers_are_jumpers no)
		(fp_line
			(start 0.299974 -0.150114)
			(end 0.299974 0.150114)
			(stroke
				(width 0.1)
				(type default)
			)
			(layer "F.Fab")
		)
		(fp_line
			(start -0.299974 -0.150114)
			(end 0.299974 -0.150114)
			(stroke
				(width 0.1)
				(type default)
			)
			(layer "F.Fab")
		)
		(fp_line
			(start 0.299974 0.150114)
			(end -0.299974 0.150114)
			(stroke
				(width 0.1)
				(type default)
			)
			(layer "F.Fab")
		)
		(fp_line
			(start -0.299974 0.150114)
			(end -0.299974 -0.150114)
			(stroke
				(width 0.1)
				(type default)
			)
			(layer "F.Fab")
		)
		(pad "1" smd rect
			(at -0.2667 0 90)
			(size 0.3048 0.381)
			(layers "F.Cu" "F.Mask" "F.Paste")
			(net "P5E_CPU1_G1_TX_C_DP<5>")
		)
		(pad "2" smd rect
			(at 0.2667 0 90)
			(size 0.3048 0.381)
			(layers "F.Cu" "F.Mask" "F.Paste")
			(net "P5E_CPU1_G1_TX_DP<5>")
		)
	)
	(footprint ""
		(layer "F.Cu")
		(at 170.3324 -384.6068 180)
		(property "Reference" "L7"
			(at 0 0 180)
			(layer "F.SilkS")
			(hide yes)
			(effects
				(font
					(size 1.27 1.27)
				)
			)
		)
		(property "Value" ""
			(at 0 0 180)
			(layer "F.Fab")
			(effects
				(font
					(size 1.27 1.27)
				)
			)
		)
		(duplicate_pad_numbers_are_jumpers no)
		(fp_line
			(start 1.63576 0.8128)
			(end -1.63576 0.8128)
			(stroke
				(width 0.1524)
				(type default)
			)
			(layer "F.SilkS")
		)
		(fp_line
			(start 1.63576 -0.8128)
			(end 1.63576 0.8128)
			(stroke
				(width 0.1524)
				(type default)
			)
			(layer "F.SilkS")
		)
		(fp_line
			(start -1.63576 -0.8128)
			(end 1.63576 -0.8128)
			(stroke
				(width 0.1524)
				(type default)
			)
			(layer "F.SilkS")
		)
		(fp_line
			(start -1.63576 -0.8128)
			(end -1.63576 0.8128)
			(stroke
				(width 0.1524)
				(type default)
			)
			(layer "F.SilkS")
		)
		(fp_line
			(start 1.560576 0.7366)
			(end 1.560576 -0.738632)
			(stroke
				(width 0.1)
				(type default)
			)
			(layer "F.Fab")
		)
		(fp_line
			(start 1.560576 -0.738632)
			(end -1.56083 -0.738632)
			(stroke
				(width 0.1)
				(type default)
			)
			(layer "F.Fab")
		)
		(fp_line
			(start 1.524 0.7366)
			(end 1.560576 0.7366)
			(stroke
				(width 0.1)
				(type default)
			)
			(layer "F.Fab")
		)
		(fp_line
			(start -1.524 0.7366)
			(end 1.524 0.7366)
			(stroke
				(width 0.1)
				(type default)
			)
			(layer "F.Fab")
		)
		(fp_line
			(start -1.56083 0.7366)
			(end -1.524 0.7366)
			(stroke
				(width 0.1)
				(type default)
			)
			(layer "F.Fab")
		)
		(fp_line
			(start -1.56083 -0.738632)
			(end -1.56083 0.7366)
			(stroke
				(width 0.1)
				(type default)
			)
			(layer "F.Fab")
		)
		(pad "1" smd rect
			(at -0.94996 0)
			(size 1.1176 1.3716)
			(layers "F.Cu" "F.Mask" "F.Paste")
			(net "P1V8_CPU1_RT_1D")
		)
		(pad "2" smd rect
			(at 0.94996 0)
			(size 1.1176 1.3716)
			(layers "F.Cu" "F.Mask" "F.Paste")
			(net "P1V8_CPU1_RT2_1A")
		)
	)
	(footprint ""
		(layer "F.Cu")
		(at 214.43188 -50.637948 90)
		(property "Reference" "R3754"
			(at 0 0 90)
			(layer "F.SilkS")
			(hide yes)
			(effects
				(font
					(size 1.27 1.27)
				)
			)
		)
		(property "Value" ""
			(at 0 0 90)
			(layer "F.Fab")
			(effects
				(font
					(size 1.27 1.27)
				)
			)
		)
		(duplicate_pad_numbers_are_jumpers no)
		(fp_line
			(start 0.7874 -0.4064)
			(end 0.7874 0.4064)
			(stroke
				(width 0.1524)
				(type default)
			)
			(layer "F.SilkS")
		)
		(fp_line
			(start -0.7874 -0.4064)
			(end 0.7874 -0.4064)
			(stroke
				(width 0.1524)
				(type default)
			)
			(layer "F.SilkS")
		)
		(fp_line
			(start 0.7874 0.4064)
			(end -0.7874 0.4064)
			(stroke
				(width 0.1524)
				(type default)
			)
			(layer "F.SilkS")
		)
		(fp_line
			(start -0.7874 0.4064)
			(end -0.7874 -0.4064)
			(stroke
				(width 0.1524)
				(type default)
			)
			(layer "F.SilkS")
		)
		(fp_line
			(start -0.12065 -0.305054)
			(end -0.12065 -0.2794)
			(stroke
				(width 0.1)
				(type default)
			)
			(layer "F.Fab")
		)
		(fp_line
			(start -0.67945 -0.305054)
			(end -0.12065 -0.305054)
			(stroke
				(width 0.1)
				(type default)
			)
			(layer "F.Fab")
		)
		(fp_line
			(start 0.67945 -0.3048)
			(end 0.67945 0.3048)
			(stroke
				(width 0.1)
				(type default)
			)
			(layer "F.Fab")
		)
		(fp_line
			(start 0.12065 -0.3048)
			(end 0.67945 -0.3048)
			(stroke
				(width 0.1)
				(type default)
			)
			(layer "F.Fab")
		)
		(fp_line
			(start 0.12065 -0.2794)
			(end 0.12065 -0.3048)
			(stroke
				(width 0.1)
				(type default)
			)
			(layer "F.Fab")
		)
		(fp_line
			(start -0.12065 -0.2794)
			(end 0.12065 -0.2794)
			(stroke
				(width 0.1)
				(type default)
			)
			(layer "F.Fab")
		)
		(fp_line
			(start 0.120396 0.2794)
			(end -0.12065 0.2794)
			(stroke
				(width 0.1)
				(type default)
			)
			(layer "F.Fab")
		)
		(fp_line
			(start -0.12065 0.2794)
			(end -0.12065 0.3048)
			(stroke
				(width 0.1)
				(type default)
			)
			(layer "F.Fab")
		)
		(fp_line
			(start 0.67945 0.3048)
			(end 0.120396 0.3048)
			(stroke
				(width 0.1)
				(type default)
			)
			(layer "F.Fab")
		)
		(fp_line
			(start 0.120396 0.3048)
			(end 0.120396 0.2794)
			(stroke
				(width 0.1)
				(type default)
			)
			(layer "F.Fab")
		)
		(fp_line
			(start -0.12065 0.3048)
			(end -0.67945 0.3048)
			(stroke
				(width 0.1)
				(type default)
			)
			(layer "F.Fab")
		)
		(fp_line
			(start -0.67945 0.3048)
			(end -0.67945 -0.305054)
			(stroke
				(width 0.1)
				(type default)
			)
			(layer "F.Fab")
		)
		(pad "1" smd circle
			(at -0.40005 0 90)
			(size 0 0)
			(layers "F.Cu" "F.Mask" "F.Paste")
			(net "SMB_INA230_2_3V3AUX_SCL_R")
		)
		(pad "2" smd circle
			(at 0.40005 0 90)
			(size 0 0)
			(layers "F.Cu" "F.Mask" "F.Paste")
			(net "SMB_INA230_2_3V3AUX_SCL_R1")
		)
	)
	(footprint ""
		(layer "F.Cu")
		(at 135.118094 -151.67356 -90)
		(property "Reference" "PC345_9"
			(at 0 0 270)
			(layer "F.SilkS")
			(hide yes)
			(effects
				(font
					(size 1.27 1.27)
				)
			)
		)
		(property "Value" ""
			(at 0 0 270)
			(layer "F.Fab")
			(effects
				(font
					(size 1.27 1.27)
				)
			)
		)
		(duplicate_pad_numbers_are_jumpers no)
		(fp_line
			(start -0.7874 0.4064)
			(end -0.7874 -0.4064)
			(stroke
				(width 0.1524)
				(type default)
			)
			(layer "F.SilkS")
		)
		(fp_line
			(start 0.7874 0.4064)
			(end -0.7874 0.4064)
			(stroke
				(width 0.1524)
				(type default)
			)
			(layer "F.SilkS")
		)
		(fp_line
			(start -0.7874 -0.4064)
			(end 0.7874 -0.4064)
			(stroke
				(width 0.1524)
				(type default)
			)
			(layer "F.SilkS")
		)
		(fp_line
			(start 0.7874 -0.4064)
			(end 0.7874 0.4064)
			(stroke
				(width 0.1524)
				(type default)
			)
			(layer "F.SilkS")
		)
		(fp_line
			(start -0.67945 0.3048)
			(end -0.67945 -0.305054)
			(stroke
				(width 0.1)
				(type default)
			)
			(layer "F.Fab")
		)
		(fp_line
			(start -0.12065 0.3048)
			(end -0.67945 0.3048)
			(stroke
				(width 0.1)
				(type default)
			)
			(layer "F.Fab")
		)
		(fp_line
			(start 0.120396 0.3048)
			(end 0.120396 0.2794)
			(stroke
				(width 0.1)
				(type default)
			)
			(layer "F.Fab")
		)
		(fp_line
			(start 0.67945 0.3048)
			(end 0.120396 0.3048)
			(stroke
				(width 0.1)
				(type default)
			)
			(layer "F.Fab")
		)
		(fp_line
			(start -0.12065 0.2794)
			(end -0.12065 0.3048)
			(stroke
				(width 0.1)
				(type default)
			)
			(layer "F.Fab")
		)
		(fp_line
			(start 0.120396 0.2794)
			(end -0.12065 0.2794)
			(stroke
				(width 0.1)
				(type default)
			)
			(layer "F.Fab")
		)
		(fp_line
			(start -0.12065 -0.2794)
			(end 0.12065 -0.2794)
			(stroke
				(width 0.1)
				(type default)
			)
			(layer "F.Fab")
		)
		(fp_line
			(start 0.12065 -0.2794)
			(end 0.12065 -0.3048)
			(stroke
				(width 0.1)
				(type default)
			)
			(layer "F.Fab")
		)
		(fp_line
			(start 0.12065 -0.3048)
			(end 0.67945 -0.3048)
			(stroke
				(width 0.1)
				(type default)
			)
			(layer "F.Fab")
		)
		(fp_line
			(start 0.67945 -0.3048)
			(end 0.67945 0.3048)
			(stroke
				(width 0.1)
				(type default)
			)
			(layer "F.Fab")
		)
		(fp_line
			(start -0.67945 -0.305054)
			(end -0.12065 -0.305054)
			(stroke
				(width 0.1)
				(type default)
			)
			(layer "F.Fab")
		)
		(fp_line
			(start -0.12065 -0.305054)
			(end -0.12065 -0.2794)
			(stroke
				(width 0.1)
				(type default)
			)
			(layer "F.Fab")
		)
		(pad "1" smd circle
			(at -0.40005 0 270)
			(size 0 0)
			(layers "F.Cu" "F.Mask" "F.Paste")
			(net "PVDDCR_CPU0_P1_VCCS")
		)
		(pad "2" smd circle
			(at 0.40005 0 270)
			(size 0 0)
			(layers "F.Cu" "F.Mask" "F.Paste")
			(net "GND")
		)
	)
)
